FILE_TYPE = MACRO_DRAWING;
SET COLOR_WIRE YELLOW;
SET COLOR_PROP ORANGE;
SET COLOR_DOT WHITE;
SET COLOR_ARC YELLOW;
SET COLOR_BODY GREEN;
SET COLOR_NOTE PURPLE;
SET PROP_DISPLAY VALUE;
SET PAGE_NUMBER P8;
FORCEADD QUANTA_TITLE_BLOCK_C..1
(5975 -1625);
FORCEPROP 1 LAST CUSTOM_TXT_CDS <NAME_2>
J 0
(2800 -1575);
FORCEPROP 1 LAST CUSTOM_TXT_CDS <NAME_1>
J 0
(2800 -1450);
FORCEPROP 1 LAST CUSTOM_TXT_CDS <Q_NUMBER>
J 0
(4572 -1522);
DISPLAY 1.212766 (4572 -1522);
FORCEPROP 1 LAST CUSTOM_TXT_CDS <Q_PROJ>
J 0
(3593 -1523);
DISPLAY 1.212766 (3593 -1523);
FORCEPROP 1 LAST CUSTOM_TXT_CDS <Q_REV>
J 0
(5791 -1522);
DISPLAY 1.212766 (5791 -1522);
FORCEPROP 1 LAST CUSTOM_TXT_CDS <CON_LAST_MODIFIED>
J 0
(4090 -1610);
DISPLAY 0.978723 (4090 -1610);
FORCEPROP 1 LAST CUSTOM_TXT_CDS <CON_PAGE_NUM> OF <CON_TOTAL_PAGES>
J 0
(5529 -1607);
DISPLAY 0.978723 (5529 -1607);
FORCEPROP 1 LAST Q_TITLE BLCOK DIAGRAM - CLOCK
J 0
(-3391 -1599);
DISPLAY 2.446809 (-3391 -1599);
PAINT GREEN (-3391 -1599);
FORCEPROP 1 LAST Q_DEPT 
J 1
(2212 -1576);
DISPLAY 1.957447 (2212 -1576);
PAINT GREEN (2212 -1576);
FORCEPROP 1 LAST COMMENT_BODY TRUE
J 0
(5987 -1638);
DISPLAY 0.978723 (5987 -1638);
PAINT GREEN (5987 -1638);
DISPLAY INVISIBLE (5987 -1638);
FORCEPROP 2 LAST PAGE_BORDER TRUE
J 0
(-1915 3625);
DISPLAY 0.638298 (-1915 3625);
PAINT PINK (-1915 3625);
DISPLAY INVISIBLE (-1915 3625);
FORCEPROP 1 LAST CDS_LMAN_SYM_OUTLINE -9475,6775,100,-125
J 0
(5975 -1625);
DISPLAY 0.468085 (5975 -1625);
PAINT GREEN (5975 -1625);
DISPLAY INVISIBLE (5975 -1625);
FORCEPROP 2 LAST CDS_LIB pure_quanta
J 0
(5975 -1625);
PAINT MONO (5975 -1625);
DISPLAY INVISIBLE (5975 -1625);
FORCEPROP 2 LAST CDS_XR_PAGE_TITLE CR-8 : @S9S_MB_2U_LIB.S9S_MB_2U(SCH_1):PAGE8
J 0
(-1915 3625);
DISPLAY 0.638298 (-1915 3625);
PAINT PINK (-1915 3625);
DISPLAY INVISIBLE (-1915 3625);
FORCEPROP 2 LAST CUSTOM_TXT_CDS <XR_PAGE_TITLE>
J 0
(-1915 3625);
DISPLAY 0.638298 (-1915 3625);
PAINT PINK (-1915 3625);
DISPLAY INVISIBLE (-1915 3625);
FORCEPROP 0 LAST CDS_CON_LAST_MODIFIED Thu Aug 24 16:11:59 2023
J 0
(4090 -1610);
PAINT MONO (4090 -1610);
DISPLAY INVISIBLE (4090 -1610);
FORCENOTE
$CDS_IMAGE|F0T_MB_CLK_diagram_20211222_rev1.jpg|8277|6104
(1325 1800) 0;
DISPLAY LEFT (1325 1800);
QUIT
